(kicad_pcb
	(version 20260206)
	(generator "pcbnew")
	(generator_version "10.0")
	(general
		(thickness 1.6)
		(legacy_teardrops no)
	)
	(paper "A4")
	(title_block
		(title "pdpb — Lightning_PDPB_BRD.brd")
		(comment 1 "Lightning (Wiwynn / Facebook NVMe JBOF) / footprint 378 of 1140 (J19), pads 1-114 of 202")
	)
	(layers
		(0 "F.Cu" signal "TOP")
		(4 "In1.Cu" signal "L2GND")
		(6 "In2.Cu" signal "L3")
		(8 "In3.Cu" signal "L4VCC")
		(10 "In4.Cu" signal "L5VCC")
		(12 "In5.Cu" signal "L6")
		(14 "In6.Cu" signal "L7GND")
		(2 "B.Cu" signal "BOTTOM")
		(9 "F.Adhes" user "F.Adhesive")
		(11 "B.Adhes" user "B.Adhesive")
		(13 "F.Paste" user "Package Geometry/Pastemask Top")
		(15 "B.Paste" user "Package Geometry/Pastemask Bottom")
		(5 "F.SilkS" user "Ref Des/Silkscreen Top")
		(7 "B.SilkS" user "Ref Des/Silkscreen Bottom")
		(1 "F.Mask" user "Board Geometry/Soldermask Top")
		(3 "B.Mask" user "Board Geometry/Soldermask Bottom")
		(17 "Dwgs.User" user "User.Drawings")
		(19 "Cmts.User" user "User.Comments")
		(21 "Eco1.User" user "User.Eco1")
		(23 "Eco2.User" user "User.Eco2")
		(25 "Edge.Cuts" user "Board Geometry/Outline")
		(27 "Margin" user)
		(31 "F.CrtYd" user "Package Geometry/Place Bound Top")
		(29 "B.CrtYd" user "Package Geometry/Place Bound Bottom")
		(35 "F.Fab" user "Ref Des/Assembly Top")
		(33 "B.Fab" user "Ref Des/Assembly Bottom")
	)
	(footprint ""
		(layer "F.Cu")
		(at 2.999994 -193.142108 90)
		(property "Reference" "J19"
			(at 0 0 90)
			(layer "F.SilkS")
			(hide yes)
			(effects
				(font
					(size 1.27 1.27)
				)
			)
		)
		(property "Value" "PCISLT200-5-GP-U"
			(at -48.7045 -6.7818 90)
			(unlocked yes)
			(layer "F.Fab")
			(hide yes)
			(effects
				(font
					(size 1.016 1.016)
					(thickness 0.1524)
				)
			)
		)
		(property "Device Type" "G639F200221431HR-U"
			(at -48.7045 -8.3058 90)
			(unlocked yes)
			(layer "F.Fab")
			(hide yes)
			(effects
				(font
					(size 1.016 1.016)
					(thickness 0.1524)
				)
			)
		)
		(duplicate_pad_numbers_are_jumpers no)
		(pad "" np_thru_hole circle
			(at -47.999904 0 90)
			(size 0.254 0.254)
			(drill 2.2098)
			(layers "*.Cu" "*.Mask")
			(clearance 1.3335)
			(thermal_gap 1.3335)
		)
		(pad "" np_thru_hole circle
			(at 47.999904 0 90)
			(size 0.254 0.254)
			(drill 2.2098)
			(layers "*.Cu" "*.Mask")
			(clearance 1.3335)
			(thermal_gap 1.3335)
		)
		(pad "A1" smd rect
			(at -41.20007 -0.750062 90)
			(size 0.508 2.4892)
			(layers "F.Cu" "F.Mask" "F.Paste")
			(net "GND")
		)
		(pad "A2" smd rect
			(at -40.39997 -0.750062 90)
			(size 0.508 2.4892)
			(layers "F.Cu" "F.Mask" "F.Paste")
			(net "PE_TX1_DR14_N")
		)
		(pad "A3" smd rect
			(at -39.600124 -0.750062 90)
			(size 0.508 2.4892)
			(layers "F.Cu" "F.Mask" "F.Paste")
			(net "PE_TX1_DR14_P")
		)
		(pad "A4" smd rect
			(at -38.800024 -0.750062 90)
			(size 0.508 2.4892)
			(layers "F.Cu" "F.Mask" "F.Paste")
			(net "GND")
		)
		(pad "A5" smd rect
			(at -37.999924 -0.750062 90)
			(size 0.508 2.4892)
			(layers "F.Cu" "F.Mask" "F.Paste")
			(net "GND")
		)
		(pad "A6" smd rect
			(at -37.200078 -0.750062 90)
			(size 0.508 2.4892)
			(layers "F.Cu" "F.Mask" "F.Paste")
			(net "PE_TX2_DR14_N")
		)
		(pad "A7" smd rect
			(at -36.399978 -0.750062 90)
			(size 0.508 2.4892)
			(layers "F.Cu" "F.Mask" "F.Paste")
			(net "PE_TX2_DR14_P")
		)
		(pad "A8" smd rect
			(at -35.599878 -0.750062 90)
			(size 0.508 2.4892)
			(layers "F.Cu" "F.Mask" "F.Paste")
			(net "GND")
		)
		(pad "A9" smd rect
			(at -34.800032 -0.750062 90)
			(size 0.508 2.4892)
			(layers "F.Cu" "F.Mask" "F.Paste")
			(net "GND")
		)
		(pad "A10" smd rect
			(at -33.999932 -0.750062 90)
			(size 0.508 2.4892)
			(layers "F.Cu" "F.Mask" "F.Paste")
			(net "PE_TX3_DR14_N")
		)
		(pad "A11" smd rect
			(at -33.200086 -0.750062 90)
			(size 0.508 2.4892)
			(layers "F.Cu" "F.Mask" "F.Paste")
			(net "PE_TX3_DR14_P")
		)
		(pad "A12" smd rect
			(at -32.399986 -0.750062 90)
			(size 0.508 2.4892)
			(layers "F.Cu" "F.Mask" "F.Paste")
			(net "GND")
		)
		(pad "A13" smd rect
			(at -31.599886 -0.750062 90)
			(size 0.508 2.4892)
			(layers "F.Cu" "F.Mask" "F.Paste")
			(net "GND")
		)
		(pad "A14" smd rect
			(at -30.80004 -0.750062 90)
			(size 0.508 2.4892)
			(layers "F.Cu" "F.Mask" "F.Paste")
			(net "PE_TX4_DR14_N")
		)
		(pad "A15" smd rect
			(at -29.99994 -0.750062 90)
			(size 0.508 2.4892)
			(layers "F.Cu" "F.Mask" "F.Paste")
			(net "PE_TX4_DR14_P")
		)
		(pad "A16" smd rect
			(at -29.200094 -0.750062 90)
			(size 0.508 2.4892)
			(layers "F.Cu" "F.Mask" "F.Paste")
			(net "GND")
		)
		(pad "A17" smd rect
			(at -28.399994 -0.750062 90)
			(size 0.508 2.4892)
			(layers "F.Cu" "F.Mask" "F.Paste")
			(net "SSD14_CLK0_OE_R_N")
		)
		(pad "A18" smd rect
			(at -27.599894 -0.750062 90)
			(size 0.508 2.4892)
			(layers "F.Cu" "F.Mask" "F.Paste")
			(net "SSD9_PWREN")
		)
		(pad "A19" smd rect
			(at -26.800048 -0.750062 90)
			(size 0.508 2.4892)
			(layers "F.Cu" "F.Mask" "F.Paste")
			(net "ATTN_LED_DR9_N")
		)
		(pad "A20" smd rect
			(at -25.999948 -0.750062 90)
			(size 0.508 2.4892)
			(layers "F.Cu" "F.Mask" "F.Paste")
			(net "SSD9_CLK0_OE_R_N")
		)
		(pad "A21" smd rect
			(at -25.200102 -0.750062 90)
			(size 0.508 2.4892)
			(layers "F.Cu" "F.Mask" "F.Paste")
			(net "GND")
		)
		(pad "A22" smd rect
			(at -24.400002 -0.750062 90)
			(size 0.508 2.4892)
			(layers "F.Cu" "F.Mask" "F.Paste")
			(net "PE_TX1_DR13_N")
		)
		(pad "A23" smd rect
			(at -23.599902 -0.750062 90)
			(size 0.508 2.4892)
			(layers "F.Cu" "F.Mask" "F.Paste")
			(net "PE_TX1_DR13_P")
		)
		(pad "A24" smd rect
			(at -22.800056 -0.750062 90)
			(size 0.508 2.4892)
			(layers "F.Cu" "F.Mask" "F.Paste")
			(net "GND")
		)
		(pad "A25" smd rect
			(at -21.999956 -0.750062 90)
			(size 0.508 2.4892)
			(layers "F.Cu" "F.Mask" "F.Paste")
			(net "GND")
		)
		(pad "A26" smd rect
			(at -21.20011 -0.750062 90)
			(size 0.508 2.4892)
			(layers "F.Cu" "F.Mask" "F.Paste")
			(net "PE_TX2_DR13_N")
		)
		(pad "A27" smd rect
			(at -20.40001 -0.750062 90)
			(size 0.508 2.4892)
			(layers "F.Cu" "F.Mask" "F.Paste")
			(net "PE_TX2_DR13_P")
		)
		(pad "A28" smd rect
			(at -19.59991 -0.750062 90)
			(size 0.508 2.4892)
			(layers "F.Cu" "F.Mask" "F.Paste")
			(net "GND")
		)
		(pad "A29" smd rect
			(at -18.800064 -0.750062 90)
			(size 0.508 2.4892)
			(layers "F.Cu" "F.Mask" "F.Paste")
			(net "GND")
		)
		(pad "A30" smd rect
			(at -17.999964 -0.750062 90)
			(size 0.508 2.4892)
			(layers "F.Cu" "F.Mask" "F.Paste")
			(net "PE_TX3_DR13_N")
		)
		(pad "A31" smd rect
			(at -17.200118 -0.750062 90)
			(size 0.508 2.4892)
			(layers "F.Cu" "F.Mask" "F.Paste")
			(net "PE_TX3_DR13_P")
		)
		(pad "A32" smd rect
			(at -16.400018 -0.750062 90)
			(size 0.508 2.4892)
			(layers "F.Cu" "F.Mask" "F.Paste")
			(net "GND")
		)
		(pad "A33" smd rect
			(at -15.599918 -0.750062 90)
			(size 0.508 2.4892)
			(layers "F.Cu" "F.Mask" "F.Paste")
			(net "GND")
		)
		(pad "A34" smd rect
			(at -14.800072 -0.750062 90)
			(size 0.508 2.4892)
			(layers "F.Cu" "F.Mask" "F.Paste")
			(net "PE_TX4_DR13_N")
		)
		(pad "A35" smd rect
			(at -13.999972 -0.750062 90)
			(size 0.508 2.4892)
			(layers "F.Cu" "F.Mask" "F.Paste")
			(net "PE_TX4_DR13_P")
		)
		(pad "A36" smd rect
			(at -13.200126 -0.750062 90)
			(size 0.508 2.4892)
			(layers "F.Cu" "F.Mask" "F.Paste")
			(net "GND")
		)
		(pad "A37" smd rect
			(at -12.400026 -0.750062 90)
			(size 0.508 2.4892)
			(layers "F.Cu" "F.Mask" "F.Paste")
			(net "GND")
		)
		(pad "A38" smd rect
			(at -11.599926 -0.750062 90)
			(size 0.508 2.4892)
			(layers "F.Cu" "F.Mask" "F.Paste")
			(net "PE_TX1_DR9_N")
		)
		(pad "A39" smd rect
			(at -10.80008 -0.750062 90)
			(size 0.508 2.4892)
			(layers "F.Cu" "F.Mask" "F.Paste")
			(net "PE_TX1_DR9_P")
		)
		(pad "A40" smd rect
			(at -9.99998 -0.750062 90)
			(size 0.508 2.4892)
			(layers "F.Cu" "F.Mask" "F.Paste")
			(net "GND")
		)
		(pad "A41" smd rect
			(at -9.19988 -0.750062 90)
			(size 0.508 2.4892)
			(layers "F.Cu" "F.Mask" "F.Paste")
			(net "GND")
		)
		(pad "A42" smd rect
			(at -8.400034 -0.750062 90)
			(size 0.508 2.4892)
			(layers "F.Cu" "F.Mask" "F.Paste")
			(net "PE_TX2_DR9_N")
		)
		(pad "A43" smd rect
			(at -7.599934 -0.750062 90)
			(size 0.508 2.4892)
			(layers "F.Cu" "F.Mask" "F.Paste")
			(net "PE_TX2_DR9_P")
		)
		(pad "A44" smd rect
			(at -6.800088 -0.750062 90)
			(size 0.508 2.4892)
			(layers "F.Cu" "F.Mask" "F.Paste")
			(net "GND")
		)
		(pad "A45" smd rect
			(at -2.800096 -0.750062 90)
			(size 0.508 2.4892)
			(layers "F.Cu" "F.Mask" "F.Paste")
			(net "SSD9_PERST_N")
		)
		(pad "A46" smd rect
			(at -1.999996 -0.750062 90)
			(size 0.508 2.4892)
			(layers "F.Cu" "F.Mask" "F.Paste")
			(net "SSD13_PERST_N")
		)
		(pad "A47" smd rect
			(at -1.199896 -0.750062 90)
			(size 0.508 2.4892)
			(layers "F.Cu" "F.Mask" "F.Paste")
			(net "GND")
		)
		(pad "A48" smd rect
			(at -0.40005 -0.750062 90)
			(size 0.508 2.4892)
			(layers "F.Cu" "F.Mask" "F.Paste")
			(net "PE_TX3_DR9_N")
		)
		(pad "A49" smd rect
			(at 0.40005 -0.750062 90)
			(size 0.508 2.4892)
			(layers "F.Cu" "F.Mask" "F.Paste")
			(net "PE_TX3_DR9_P")
		)
		(pad "A50" smd rect
			(at 1.199896 -0.750062 90)
			(size 0.508 2.4892)
			(layers "F.Cu" "F.Mask" "F.Paste")
			(net "GND")
		)
		(pad "A51" smd rect
			(at 1.999996 -0.750062 90)
			(size 0.508 2.4892)
			(layers "F.Cu" "F.Mask" "F.Paste")
			(net "GND")
		)
		(pad "A52" smd rect
			(at 2.800096 -0.750062 90)
			(size 0.508 2.4892)
			(layers "F.Cu" "F.Mask" "F.Paste")
			(net "PE_TX4_DR9_N")
		)
		(pad "A53" smd rect
			(at 3.599942 -0.750062 90)
			(size 0.508 2.4892)
			(layers "F.Cu" "F.Mask" "F.Paste")
			(net "PE_TX4_DR9_P")
		)
		(pad "A54" smd rect
			(at 4.400042 -0.750062 90)
			(size 0.508 2.4892)
			(layers "F.Cu" "F.Mask" "F.Paste")
			(net "GND")
		)
		(pad "A55" smd rect
			(at 5.199888 -0.750062 90)
			(size 0.508 2.4892)
			(layers "F.Cu" "F.Mask" "F.Paste")
			(net "SSD13_PWREN")
		)
		(pad "A56" smd rect
			(at 5.999988 -0.750062 90)
			(size 0.508 2.4892)
			(layers "F.Cu" "F.Mask" "F.Paste")
			(net "ATTN_LED_DR13_N")
		)
		(pad "A57" smd rect
			(at 6.800088 -0.750062 90)
			(size 0.508 2.4892)
			(layers "F.Cu" "F.Mask" "F.Paste")
			(net "SSD13_CLK0_OE_R_N")
		)
		(pad "A58" smd rect
			(at 7.599934 -0.750062 90)
			(size 0.508 2.4892)
			(layers "F.Cu" "F.Mask" "F.Paste")
			(net "GND")
		)
		(pad "A59" smd rect
			(at 8.400034 -0.750062 90)
			(size 0.508 2.4892)
			(layers "F.Cu" "F.Mask" "F.Paste")
			(net "PE_TX1_DR8_N")
		)
		(pad "A60" smd rect
			(at 9.19988 -0.750062 90)
			(size 0.508 2.4892)
			(layers "F.Cu" "F.Mask" "F.Paste")
			(net "PE_TX1_DR8_P")
		)
		(pad "A61" smd rect
			(at 9.99998 -0.750062 90)
			(size 0.508 2.4892)
			(layers "F.Cu" "F.Mask" "F.Paste")
			(net "GND")
		)
		(pad "A62" smd rect
			(at 10.80008 -0.750062 90)
			(size 0.508 2.4892)
			(layers "F.Cu" "F.Mask" "F.Paste")
			(net "GND")
		)
		(pad "A63" smd rect
			(at 11.599926 -0.750062 90)
			(size 0.508 2.4892)
			(layers "F.Cu" "F.Mask" "F.Paste")
			(net "PE_TX2_DR8_N")
		)
		(pad "A64" smd rect
			(at 12.400026 -0.750062 90)
			(size 0.508 2.4892)
			(layers "F.Cu" "F.Mask" "F.Paste")
			(net "PE_TX2_DR8_P")
		)
		(pad "A65" smd rect
			(at 13.200126 -0.750062 90)
			(size 0.508 2.4892)
			(layers "F.Cu" "F.Mask" "F.Paste")
			(net "GND")
		)
		(pad "A66" smd rect
			(at 13.999972 -0.750062 90)
			(size 0.508 2.4892)
			(layers "F.Cu" "F.Mask" "F.Paste")
			(net "GND")
		)
		(pad "A67" smd rect
			(at 14.800072 -0.750062 90)
			(size 0.508 2.4892)
			(layers "F.Cu" "F.Mask" "F.Paste")
			(net "PE_TX3_DR8_N")
		)
		(pad "A68" smd rect
			(at 15.599918 -0.750062 90)
			(size 0.508 2.4892)
			(layers "F.Cu" "F.Mask" "F.Paste")
			(net "PE_TX3_DR8_P")
		)
		(pad "A69" smd rect
			(at 16.400018 -0.750062 90)
			(size 0.508 2.4892)
			(layers "F.Cu" "F.Mask" "F.Paste")
			(net "GND")
		)
		(pad "A70" smd rect
			(at 17.200118 -0.750062 90)
			(size 0.508 2.4892)
			(layers "F.Cu" "F.Mask" "F.Paste")
			(net "GND")
		)
		(pad "A71" smd rect
			(at 17.999964 -0.750062 90)
			(size 0.508 2.4892)
			(layers "F.Cu" "F.Mask" "F.Paste")
			(net "PE_TX4_DR8_N")
		)
		(pad "A72" smd rect
			(at 18.800064 -0.750062 90)
			(size 0.508 2.4892)
			(layers "F.Cu" "F.Mask" "F.Paste")
			(net "PE_TX4_DR8_P")
		)
		(pad "A73" smd rect
			(at 19.59991 -0.750062 90)
			(size 0.508 2.4892)
			(layers "F.Cu" "F.Mask" "F.Paste")
			(net "GND")
		)
		(pad "A74" smd rect
			(at 20.40001 -0.750062 90)
			(size 0.508 2.4892)
			(layers "F.Cu" "F.Mask" "F.Paste")
			(net "GND")
		)
		(pad "A75" smd rect
			(at 21.20011 -0.750062 90)
			(size 0.508 2.4892)
			(layers "F.Cu" "F.Mask" "F.Paste")
			(net "PE_TX1_DR12_N")
		)
		(pad "A76" smd rect
			(at 21.999956 -0.750062 90)
			(size 0.508 2.4892)
			(layers "F.Cu" "F.Mask" "F.Paste")
			(net "PE_TX1_DR12_P")
		)
		(pad "A77" smd rect
			(at 22.800056 -0.750062 90)
			(size 0.508 2.4892)
			(layers "F.Cu" "F.Mask" "F.Paste")
			(net "GND")
		)
		(pad "A78" smd rect
			(at 23.599902 -0.750062 90)
			(size 0.508 2.4892)
			(layers "F.Cu" "F.Mask" "F.Paste")
			(net "GND")
		)
		(pad "A79" smd rect
			(at 24.400002 -0.750062 90)
			(size 0.508 2.4892)
			(layers "F.Cu" "F.Mask" "F.Paste")
			(net "PE_TX2_DR12_N")
		)
		(pad "A80" smd rect
			(at 25.200102 -0.750062 90)
			(size 0.508 2.4892)
			(layers "F.Cu" "F.Mask" "F.Paste")
			(net "PE_TX2_DR12_P")
		)
		(pad "A81" smd rect
			(at 25.999948 -0.750062 90)
			(size 0.508 2.4892)
			(layers "F.Cu" "F.Mask" "F.Paste")
			(net "GND")
		)
		(pad "A82" smd rect
			(at 26.800048 -0.750062 90)
			(size 0.508 2.4892)
			(layers "F.Cu" "F.Mask" "F.Paste")
			(net "GND")
		)
		(pad "A83" smd rect
			(at 27.599894 -0.750062 90)
			(size 0.508 2.4892)
			(layers "F.Cu" "F.Mask" "F.Paste")
			(net "PE_TX3_DR12_N")
		)
		(pad "A84" smd rect
			(at 28.399994 -0.750062 90)
			(size 0.508 2.4892)
			(layers "F.Cu" "F.Mask" "F.Paste")
			(net "PE_TX3_DR12_P")
		)
		(pad "A85" smd rect
			(at 29.200094 -0.750062 90)
			(size 0.508 2.4892)
			(layers "F.Cu" "F.Mask" "F.Paste")
			(net "GND")
		)
		(pad "A86" smd rect
			(at 29.99994 -0.750062 90)
			(size 0.508 2.4892)
			(layers "F.Cu" "F.Mask" "F.Paste")
			(net "GND")
		)
		(pad "A87" smd rect
			(at 30.80004 -0.750062 90)
			(size 0.508 2.4892)
			(layers "F.Cu" "F.Mask" "F.Paste")
			(net "PE_TX4_DR12_N")
		)
		(pad "A88" smd rect
			(at 31.599886 -0.750062 90)
			(size 0.508 2.4892)
			(layers "F.Cu" "F.Mask" "F.Paste")
			(net "PE_TX4_DR12_P")
		)
		(pad "A89" smd rect
			(at 32.399986 -0.750062 90)
			(size 0.508 2.4892)
			(layers "F.Cu" "F.Mask" "F.Paste")
			(net "GND")
		)
		(pad "A90" smd rect
			(at 33.200086 -0.750062 90)
			(size 0.508 2.4892)
			(layers "F.Cu" "F.Mask" "F.Paste")
			(net "GND")
		)
		(pad "A91" smd rect
			(at 33.999932 -0.750062 90)
			(size 0.508 2.4892)
			(layers "F.Cu" "F.Mask" "F.Paste")
			(net "PE_TX1_DR4_N")
		)
		(pad "A92" smd rect
			(at 34.800032 -0.750062 90)
			(size 0.508 2.4892)
			(layers "F.Cu" "F.Mask" "F.Paste")
			(net "PE_TX1_DR4_P")
		)
		(pad "A93" smd rect
			(at 35.599878 -0.750062 90)
			(size 0.508 2.4892)
			(layers "F.Cu" "F.Mask" "F.Paste")
			(net "GND")
		)
		(pad "A94" smd rect
			(at 36.399978 -0.750062 90)
			(size 0.508 2.4892)
			(layers "F.Cu" "F.Mask" "F.Paste")
			(net "GND")
		)
		(pad "A95" smd rect
			(at 37.200078 -0.750062 90)
			(size 0.508 2.4892)
			(layers "F.Cu" "F.Mask" "F.Paste")
			(net "PE_TX2_DR4_N")
		)
		(pad "A96" smd rect
			(at 37.999924 -0.750062 90)
			(size 0.508 2.4892)
			(layers "F.Cu" "F.Mask" "F.Paste")
			(net "PE_TX2_DR4_P")
		)
		(pad "A97" smd rect
			(at 38.800024 -0.750062 90)
			(size 0.508 2.4892)
			(layers "F.Cu" "F.Mask" "F.Paste")
			(net "GND")
		)
		(pad "A98" smd rect
			(at 39.600124 -0.750062 90)
			(size 0.508 2.4892)
			(layers "F.Cu" "F.Mask" "F.Paste")
			(net "TRAY_ID_R")
		)
		(pad "A99" smd rect
			(at 40.39997 -0.750062 90)
			(size 0.508 2.4892)
			(layers "F.Cu" "F.Mask" "F.Paste")
			(net "SD_LATCH_RELEASE_R")
		)
		(pad "A100" smd rect
			(at 41.20007 -0.750062 90)
			(size 0.508 2.4892)
			(layers "F.Cu" "F.Mask" "F.Paste")
			(net "PCIE_MATED#_B")
		)
		(pad "B1" smd rect
			(at -41.20007 -1.131062 90)
			(size 0.508 2.4892)
			(drill
				(offset 0 0.381)
			)
			(layers "F.Cu" "F.Mask" "F.Paste")
			(net "ATTN_LED_DR14_N")
		)
		(pad "B2" smd rect
			(at -40.39997 -1.131062 90)
			(size 0.508 2.4892)
			(drill
				(offset 0 0.381)
			)
			(layers "F.Cu" "F.Mask" "F.Paste")
			(net "SSD14_PWREN")
		)
		(pad "B3" smd rect
			(at -39.600124 -1.131062 90)
			(size 0.508 2.4892)
			(drill
				(offset 0 0.381)
			)
			(layers "F.Cu" "F.Mask" "F.Paste")
			(net "GND")
		)
		(pad "B4" smd rect
			(at -38.800024 -1.131062 90)
			(size 0.508 2.4892)
			(drill
				(offset 0 0.381)
			)
			(layers "F.Cu" "F.Mask" "F.Paste")
			(net "PE_RX1_DR14_N")
		)
		(pad "B5" smd rect
			(at -37.999924 -1.131062 90)
			(size 0.508 2.4892)
			(drill
				(offset 0 0.381)
			)
			(layers "F.Cu" "F.Mask" "F.Paste")
			(net "PE_RX1_DR14_P")
		)
		(pad "B6" smd rect
			(at -37.200078 -1.131062 90)
			(size 0.508 2.4892)
			(drill
				(offset 0 0.381)
			)
			(layers "F.Cu" "F.Mask" "F.Paste")
			(net "GND")
		)
		(pad "B7" smd rect
			(at -36.399978 -1.131062 90)
			(size 0.508 2.4892)
			(drill
				(offset 0 0.381)
			)
			(layers "F.Cu" "F.Mask" "F.Paste")
			(net "GND")
		)
		(pad "B8" smd rect
			(at -35.599878 -1.131062 90)
			(size 0.508 2.4892)
			(drill
				(offset 0 0.381)
			)
			(layers "F.Cu" "F.Mask" "F.Paste")
			(net "PE_RX2_DR14_N")
		)
		(pad "B9" smd rect
			(at -34.800032 -1.131062 90)
			(size 0.508 2.4892)
			(drill
				(offset 0 0.381)
			)
			(layers "F.Cu" "F.Mask" "F.Paste")
			(net "PE_RX2_DR14_P")
		)
		(pad "B10" smd rect
			(at -33.999932 -1.131062 90)
			(size 0.508 2.4892)
			(drill
				(offset 0 0.381)
			)
			(layers "F.Cu" "F.Mask" "F.Paste")
			(net "GND")
		)
		(pad "B11" smd rect
			(at -33.200086 -1.131062 90)
			(size 0.508 2.4892)
			(drill
				(offset 0 0.381)
			)
			(layers "F.Cu" "F.Mask" "F.Paste")
			(net "GND")
		)
		(pad "B12" smd rect
			(at -32.399986 -1.131062 90)
			(size 0.508 2.4892)
			(drill
				(offset 0 0.381)
			)
			(layers "F.Cu" "F.Mask" "F.Paste")
			(net "PE_RX3_DR14_N")
		)
	)
)
